FILE_TYPE = MULTI_PHYS_TABLE;

PART 'GND_HOLE'

{========================================================================================}
:PACK_TYPE | MATERIAL | PART_NUMBER             = STANDARD | LIFECYCLE | PART_NUMBER             | JEDEC_TYPE                               | CLASS | DESCRIPTION                                       | COMPONENT_TYPE | LEAD_LENGTH | DFM_EXCLUSION ;
{========================================================================================}
 'TH'      | 'EMPTY'  | 'QUANTA_N_A'(!)         = ''       | ''        | 'QUANTA_N_A'            |'GND_C10D4-3B10'| 'IO'  | 'SPOKE MOUNTING HOLE 169'                         | ''             | ''          | ''           
 'TH'      | 'EMPTY'  | 'TMP-Q_S08_SAM_0621_1'(!) = ''       | ''        | 'TMP-Q_S08_SAM_0621_1'  |'GND_C8D3-5B8'| 'IO'  | 'GNDHOLE_C8D3-5B8'                                | ''             | ''          | ''           
 'TH'      | 'EMPTY'  | 'GND_HOLE86'(!)         = ''       | ''        | 'GND_HOLE86'            |'GND_C9D4-3B9'| 'IO'  | 'GND_C9D4-3B9'                                    | ''             | ''          | ''           
 'TH'      | 'EMPTY'  | 'TMP-QGND_HOLE242'(!)   = ''       | ''        | 'TMP-QGND_HOLE242'      |'GND_C7-77D5-42B7-77'| 'IO'  | 'GNDHOLE_C7-77D5-42B7-77'                         | ''             | ''          | ''           
 'TH'      | 'EMPTY'  | 'TMP-QGND_HOLE55'(!)    = ''       | ''        | 'TMP-QGND_HOLE55'       |'GND_C8D4-5B8'| 'IO'  | 'GNDHOLE_8PIN_C8D4-5B8'                           | ''             | ''          | ''           
 'TH'      | 'EMPTY'  | 'TMP-C_LU2_MATT_0430_1'(!) = ''       | ''        | 'TMP-C_LU2_MATT_0430_1' |'GND_C7-3D3-56B7-3_OSP'| 'IO'  | 'GND_C7-3D3-56B7-3_OSP'                           | ''             | ''          | ''           
 'TH'      | 'EMPTY'  | 'TMP-C_LU2_MATT_0430_2'(!) = ''       | ''        | 'TMP-C_LU2_MATT_0430_2' |'GND_C7-3D4B7-3_OSP'| 'IO'  | 'GND_C7-3D4B7-3_OSP'                              | ''             | ''          | ''           
 'TH'      | 'EMPTY'  | 'TMP-QGND_HOLE12'(!)    = ''       | ''        | 'TMP-QGND_HOLE12'       |'GND_C8D4B8'| 'IO'  | 'GND_C8D4B8'                                      | ''             | ''          | ''           
 'TH'      | 'EMPTY'  | 'TMP-QGND_HOLE278'(!)   = ''       | ''        | 'TMP-QGND_HOLE278'      |'GND_C10D4-5B10'| 'IO'  | 'GND_C10D4-5B10'                                  | ''             | ''          | ''           
 'TH'      | 'EMPTY'  | 'TMP-QGND_HOLE69'(!)    = ''       | ''        | 'TMP-QGND_HOLE69'       |'GND_C10D4-5'| 'IO'  | 'GND_C10D4-5'                                     | ''             | ''          | ''           
 'TH'      | 'EMPTY'  | 'TMP-QGND_HOLE286'(!)   = ''       | ''        | 'TMP-QGND_HOLE286'      |'GND_C7-3D4-5B7-3_OSP'| 'IO'  | 'GND_C7-3D4-5B7-3_OSP'                            | ''             | ''          | ''           
 'TH'      | 'EMPTY'  | 'TMP-QGND_HOLE287'(!)   = ''       | ''        | 'TMP-QGND_HOLE287'      |'GND_C7-3D3-5B7-3_OSP'| 'IO'  | 'GND_C7-3D3-5B7-3_OSP'                            | ''             | ''          | ''           
 'TH'      | 'EMPTY'  | 'TMP-QGND_HOLE81'(!)    = ''       | ''        | 'TMP-QGND_HOLE81'       |'GND_C9D4'| 'IO'  | 'GND_C9D4'                                        | ''             | ''          | ''           
 'TH'      | 'EMPTY'  | 'TMP-QGND_HOLE289'(!)   = ''       | ''        | 'TMP-QGND_HOLE289'      |'GND_C10-2D3-7B10-2_OSP'| 'IO'  | 'GND_C10-2D3-7B10-2_OSP'                          | ''             | ''          | ''           
 'TH_SEL'  | 'EMPTY'  | 'GND_HOLE194'(!)        = ''       | ''        | 'GND_HOLE194'           |'G_GND_C10-16D3-96'| 'IO'  | 'GND_C10-16D3-96'                                 | ''             | ''          | ''           
 'TH'      | 'EMPTY'  | 'GND_HOLE288'(!)        = ''       | ''        | 'GND_HOLE288'           |'GND_C10D5-7B10'| 'IO'  | 'GND_C10D5-7B10'                                  | ''             | ''          | ''           
 'TH'      | 'EMPTY'  | 'GND_HOLE46'(!)         = ''       | ''        | 'GND_HOLE46'            |'GND_C10D4B10'| 'IO'  | 'GNDHOLE_8PIN_C10D4B10'                           | ''             | ''          | ''           
 'TH'      | 'EMPTY'  | 'GND_HOLE307'(!)        = ''       | ''        | 'GND_HOLE307'           |'GND_C11D6-4B11'| 'IO'  | 'GND_C11D6-4B11'                                  | ''             | ''          | ''           
 'TH'      | 'EMPTY'  | 'GND_HOLE306'(!)        = ''       | ''        | 'GND_HOLE306'           |'GND_C11D6-2B11'| 'IO'  | 'GND_C11D6-2B11'                                  | ''             | ''          | ''           
 'TH'      | 'EMPTY'  | 'GND_HOLE311'(!)        = ''       | ''        | 'GND_HOLE311'           |'GND_C10D4-8B10'| 'IO'  | 'GND_C10D4-8B10'                                  | ''             | ''          | ''           
 'TH'      | 'EMPTY'  | 'GND_HOLE312'(!)        = ''       | ''        | 'GND_HOLE312'           |'GND_C10D3-6B10'| 'IO'  | 'GND_C10D3-6B10'                                  | ''             | ''          | ''           
 'TH'      | 'EMPTY'  | 'GND_HOLE47'(!)         = ''       | ''        | 'GND_HOLE47'            |'GND_C9D4-5B9'| 'IO'  | 'GND_C9D4-5B9'                                    | ''             | ''          | ''           
 'TH'      | 'EMPTY'  | 'GND_HOLE231'(!)        = ''       | ''        | 'GND_HOLE231'           |'GND_C8D4-3B8'| 'IO'  | 'GND_C8D4-3B8'                                    | ''             | ''          | ''           
 'TH'      | 'EMPTY'  | 'GND_HOLE277'(!)        = ''       | ''        | 'GND_HOLE277'           |'GND_R10X11D4B10X11'| 'IO'  | 'GND_R10X11D4B10X11'                              | ''             | ''          | ''           
 'TH'      | 'EMPTY'  | 'GND_HOLE315'(!)        = ''       | ''        | 'GND_HOLE315'           |'GND_C8-5D5-6B8-5'| 'IO'  | 'GND_C8-5D5-6B8-5'                                | ''             | ''          | ''           
 'TH'      | 'EMPTY'  | 'GND_HOLE318'(!)        = ''       | ''        | 'GND_HOLE318'           |'GND_C10D4-5B10_CUTB_OSP-T'| 'IO'  | 'GND_C10D4-5B10_CUTB_OSP-T'                       | ''             | ''          | ''           
 'TH'      | 'EMPTY'  | 'GND_HOLE320'(!)        = ''       | ''        | 'GND_HOLE320'           |'GND_C8-6D5-6B12_OB3-5XC6B'| 'IO'  | 'GND_C8-6D5-6B12_OB3-5XC6B'                       | ''             | ''          | ''           
 'TH'      | 'EMPTY'  | 'GND_HOLE259'(!)        = ''       | ''        | 'GND_HOLE259'           |'GND_C10D4-3B10_OSP-T'| 'IO'  | 'GND_C10D4-3B10_OSP-T'                            | ''             | ''          | ''           
 'TH'      | 'EMPTY'  | 'GND_HOLE29'(!)         = ''       | ''        | 'GND_HOLE29'            |'GND_C9D5B9'| 'IO'  | 'GND_C9D5B9'                                      | ''             | ''          | ''           
 'TH'      | 'EMPTY'  | 'GND_HOLE140'(!)        = ''       | ''        | 'GND_HOLE140'           |'GND_C10D5-5B10'| 'IO'  | 'GNDHOLE_8PIN_C10D5-5B10'                         | ''             | ''          | ''           
 'TH'      | 'EMPTY'  | 'GND_HOLE192'(!)        = ''       | ''        | 'GND_HOLE192'           |'GND_C10D3-8B10'| 'IO'  | 'GNDHOLE_C10D3-8B10'                              | ''             | ''          | ''           
 'TH'      | 'EMPTY'  | 'GND_HOLE149'(!)        = ''       | ''        | 'GND_HOLE149'           |'GND_C10D4B10'| 'IO'  | 'GNDHOLE_8PIN_C10D4B10'                           | ''             | ''          | ''           
 'TH'      | 'EMPTY'  | 'GND_HOLE325'(!)        = ''       | ''        | 'GND_HOLE325'           |'GND_R10X13-6D4B10_Y-1-8T_CUTA'| 'IO'  | 'GNDHOLE_8PIN_R10X13-6D4B10_Y-1-8T_CUTA'          | ''             | ''          | ''           
 'TH'      | 'EMPTY'  | 'GND_HOLE13'(!)         = ''       | ''        | 'GND_HOLE13'            |'GND_C8D4'| 'IO'  | 'GNDHOLE_8PIN_C8D4'                               | ''             | ''          | ''           
 'TH'      | 'EMPTY'  | 'GND_HOLE333'(!)        = ''       | ''        | 'GND_HOLE333'           |'GND_C11-6D5-6B11-6_OB16XC5-8B'| 'IO'  | 'GND_C11-6D5-6B11-6_OB16XC5-8B'                   | ''             | ''          | ''           
 'TH'      | 'EMPTY'  | 'GND_HOLE336'(!)        = ''       | ''        | 'GND_HOLE336'           |'GND_C10D3-7B10_OB5-5XC5B'| 'IO'  | 'GND_C10D3-7B10_OB5-5XC5B'                        | ''             | ''          | ''           
 'TH'      | 'EMPTY'  | 'GND_HOLE134'(!)        = ''       | ''        | 'GND_HOLE134'           |'GND_C13D5-6B13'| 'IO'  | 'GND_C13D5-6B13'                                  | ''             | ''          | ''           
 'TH'      | 'EMPTY'  | 'GND_HOLE112'(!)        = ''       | ''        | 'GND_HOLE112'           |'GND_C9D5-3B9'| 'IO'  | 'GND_C9D5-3B9'                                    | ''             | ''          | ''           
 'TH'      | 'EMPTY'  | 'GND_HOLE28'(!)         = ''       | ''        | 'GND_HOLE28'            |'GND_C9D4B9'| 'IO'  | 'GND_C9D4B9'                                      | ''             | ''          | ''           
 'TH'      | 'EMPTY'  | 'GND_HOLE344'(!)        = ''       | ''        | 'GND_HOLE344'           |'GND_C10D3-5B10'| 'IO'  | 'GND_C10D3-5B10'                                  | ''             | ''          | ''           
 'TH'      | 'EMPTY'  | 'GND_HOLE326'(!)        = ''       | ''        | 'GND_HOLE326'           |'GND_C9D4B8_OB6XC4BN'| 'IO'  | 'GND_C9D4B8_OB6XC4BN'                             | ''             | ''          | ''           
 'TH'      | 'EMPTY'  | 'GND_HOLE219'(!)        = ''       | ''        | 'GND_HOLE219'           |'GND_C9D5-41B9'| 'IO'  | 'GNDHOLE_8PIN_C9D5-41B9'                          | ''             | ''          | ''           
 'TH'      | 'EMPTY'  | 'GND_HOLE349'(!)        = ''       | ''        | 'GND_HOLE349'           |'GND_C9D4B9_OB3-5X4-5B'| 'IO'  | 'GND_C9D4B9_OB3-5X4-5B'                           | ''             | ''          | ''           
 'TH'      | 'EMPTY'  | 'GND_HOLE104'(!)        = ''       | ''        | 'GND_HOLE104'           |'GND_C9D3-2B9'| 'IO'  | 'GND_C9D3-2B9'                                    | ''             | ''          | ''           
 'TH'      | 'EMPTY'  | 'GND_HOLE21'(!)         = ''       | ''        | 'GND_HOLE21'            |'GND_C8D3-6B8'| 'IO'  | 'GND_C8D3-6B8'                                    | ''             | ''          | ''           
 'TH'      | 'EMPTY'  | 'GND_HOLE26'(!)         = ''       | ''        | 'GND_HOLE26'            |'GND_C10D3-2B10'| 'IO'  | 'GND_C10D3-2B10'                                  | ''             | ''          | ''           
 'TH'      | 'EMPTY'  | 'GND_HOLE352'(!)        = ''       | ''        | 'GND_HOLE352'           |'GND_C10D3-9B10'| 'IO'  | 'GND_C10D3-9B10'                                  | ''             | ''          | ''           
 'TH'      | 'EMPTY'  | 'GND_HOLE266'(!)        = ''       | ''        | 'GND_HOLE266'           |'GND_R9X9-5D3-6B9X9-5'| 'IO'  | 'GND_R9X9-5D3-6B9X9-5'                            | ''             | ''          | ''           
 'TH'      | 'EMPTY'  | 'GND_HOLE160'(!)        = ''       | ''        | 'GND_HOLE160'           |'GND_C7-5D4-3'| 'IO'  | 'GND_C7-5D4-3'                                    | ''             | ''          | ''           
 'TH'      | 'EMPTY'  | 'GND_HOLE319'(!)        = ''       | ''        | 'GND_HOLE319'           |'GND_C10D4B10_OB5XC5B'| 'IO'  | 'GND_C10D4B10_OB5XC5B'                            | ''             | ''          | ''           
 'TH'      | 'EMPTY'  | 'GND_HOLE264'(!)        = ''       | ''        | 'GND_HOLE264'           |'GND_C8D4B10_OB7XC5B'| 'IO'  | 'GND_C8D4B10_OB7XC5B'                             | ''             | ''          | ''           
 'TH'      | 'EMPTY'  | 'GND_HOLE16'(!)         = ''       | ''        | 'GND_HOLE16'            |'GND_C7D4B7'| 'IO'  | 'GND_C7D4B7'                                      | ''             | ''          | ''           
 'TH'      | 'EMPTY'  | 'GND_HOLE364'(!)        = ''       | ''        | 'GND_HOLE364'           |'GND_C8D4B9_OB3-5XC4-5B'| 'IO'  | 'GND_C8D4B9_OB3-5XC4-5B'                          | ''             | ''          | ''           
 'TH'      | 'EMPTY'  | 'GND_HOLE370'(!)        = ''       | ''        | 'GND_HOLE370'           |'GND_C10D4B10_OB10XC5B'| 'IO'  | 'GND_C10D4B10_OB10XC5B'                           | ''             | ''          | ''           
 'TH'      | 'EMPTY'  | 'GND_HOLE371'(!)        = ''       | ''        | 'GND_HOLE371'           |'GND_C10D3-6B10_OB3-5XC5B'| 'IO'  | 'GND_C10D3-6B10_OB3-5XC5B'                        | ''             | ''          | ''           
 'TH'      | 'EMPTY'  | 'GND_HOLE372'(!)        = ''       | ''        | 'GND_HOLE372'           |'GND_C10D3-1B10_OB3-5XC5B'| 'IO'  | 'GND_C10D3-1B10_OB3-5XC5B'                        | ''             | ''          | ''           
 'TH'      | 'EMPTY'  | 'GND_HOLE167'(!)        = ''       | ''        | 'GND_HOLE167'           |'GND_C10-16D3-5B10-16'| 'IO'  | 'GND_C10-16D3-5B10-16'                            | ''             | ''          | ''           
 'TH'      | 'EMPTY'  | 'GND_HOLE375'(!)        = ''       | ''        | 'GND_HOLE375'           |'GND_C10D5-6B10_OB3-5XC5T'| 'IO'  | 'GND_C10D5-6B10_OB3-5XC5T'                        | ''             | ''          | ''           
 'TH'      | 'EMPTY'  | 'GND_HOLE376'(!)        = ''       | ''        | 'GND_HOLE376'           |'GND_C10D5-6B10_OB3-5XC5B'| 'IO'  | 'GND_C10D5-6B10_OB3-5XC5B'                        | ''             | ''          | ''           
 'TH'      | 'EMPTY'  | 'GND_HOLE379'(!)        = ''       | ''        | 'GND_HOLE379'           |'GND_C10OB4-8X5-4B10'| 'IO'  | 'GND_C10OB4-8X5-4B10'                             | ''             | ''          | ''           
 'TH'      | 'EMPTY'  | 'GND_HOLE383'(!)        = ''       | ''        | 'GND_HOLE383'           |'GND_C10D4B8_OB3-5XC4B'| 'IO'  | 'GND_C10D4B8_OB3-5XC4B'                           | ''             | ''          | ''           
 'TH'      | 'EMPTY'  | 'GND_HOLE384'(!)        = ''       | ''        | 'GND_HOLE384'           |'GND_R15X16D4-8B10_IX0-5'| 'IO'  | 'GND_R15X16D4-8B10_IX0-5'                         | ''             | ''          | ''           
 'TH'      | 'EMPTY'  | 'GND_HOLE385'(!)        = ''       | ''        | 'GND_HOLE385'           |'GND_C10D3-6B9_OB5XC4-5B'| 'IO'  | 'GND_C10D3-6B9_OB5XC4-5B'                         | ''             | ''          | ''           
 'TH'      | 'EMPTY'  | 'GND_HOLE386'(!)        = ''       | ''        | 'GND_HOLE386'           |'GND_C10D3-6B10_OB6XC5B'| 'IO'  | 'GND_C10D3-6B10_OB6XC5B'                          | ''             | ''          | ''           
 'TH'      | 'EMPTY'  | 'GND_HOLE389'(!)        = ''       | ''        | 'GND_HOLE389'           |'GND_C10D3-1B10'| 'IO'  | 'GND_C10D3-1B10'                                  | ''             | ''          | ''           
 'TH'      | 'EMPTY'  | 'GND_HOLE243'(!)        = ''       | ''        | 'GND_HOLE243'           |'GND_C8D3-1B8'| 'IO'  | 'GND_C8D3-1B8'                                    | ''             | ''          | ''           
 'TH'      | 'EMPTY'  | 'GND_HOLE391'(!)        = ''       | ''        | 'GND_HOLE391'           |'GND_C9D3-6B9_OB9XC4-5B'| 'IO'  | 'GND_C9D3-6B9_OB9XC4-5B'                          | ''             | ''          | ''           
 'TH'      | 'EMPTY'  | 'GND_HOLE392'(!)        = ''       | ''        | 'GND_HOLE392'           |'GND_C9D3-6B9_OB5XC4-5B'| 'IO'  | 'GND_C9D3-6B9_OB5XC4-5B'                          | ''             | ''          | ''           
 'TH'      | 'EMPTY'  | 'GND_HOLE393'(!)        = ''       | ''        | 'GND_HOLE393'           |'GND_C10D3-2B10_OB3-5XC5B'| 'IO'  | 'GND_C10D3-2B10_OB3-5XC5B'                        | ''             | ''          | ''           
 'TH'      | 'EMPTY'  | 'GND_HOLE394'(!)        = ''       | ''        | 'GND_HOLE394'           |'GND_C10D3-2B10_OB3-5XC5T_RB'| 'IO'  | 'GND_C10D3-2B10_OB3-5XC5T_RB'                     | ''             | ''          | ''           
 'TH'      | 'EMPTY'  | 'GND_HOLE398'(!)        = ''       | ''        | 'GND_HOLE398'           |'GND_C10-5OBD5-5X6-5B10-5_OB4-5XC5-25B'| 'IO'  | 'GND_C10-5OBD5-5X6-5B10-5_OB4-5XC5-25B'           | ''             | ''          | ''           
 'TH'      | 'EMPTY'  | 'GND_HOLE399'(!)        = ''       | ''        | 'GND_HOLE399'           |'GND_C10D7-8X5-8B10_OB6XC5B'| 'IO'  | 'GND_C10D7-8X5-8B10_OB6XC5B'                      | ''             | ''          | ''           
 'TH'      | 'EMPTY'  | 'GND_HOLE407'(!)        = ''       | ''        | 'GND_HOLE407'           |'GND_C10D4B10_OB10XC5T_RB'| 'IO'  | 'GND_C10D4B10_OB10XC5T_RB'                        | ''             | ''          | ''           
 'TH'      | 'EMPTY'  | 'GND_HOLE423'(!)        = ''       | ''        | 'GND_HOLE423'           |'GND_C10D3-5B10_OB6XC5B'| 'IO'  | 'GND_C10D3-5B10_OB6XC5B'                          | ''             | ''          | ''           
 'TH'      | 'EMPTY'  | 'GND_HOLE45'(!)         = ''       | ''        | 'GND_HOLE45'            |'GND_C10D5B10'| 'IO'  | 'GND_C10D5B10'                                    | ''             | ''          | ''           
 'TH'      | 'EMPTY'  | 'GND_HOLE428'(!)        = ''       | ''        | 'GND_HOLE428'           |'GND_C10-16D3-96B10-16_OB7-62XC5-08B'| 'IO'  | 'GND_C10-16D3-96B10-16_OB7-62XC5-08B'             | ''             | ''          | ''           
 'TH'      | 'EMPTY'  | 'SP_GND_HOLE428'(!)     = ''       | ''        | 'SP_GND_HOLE428'        |'G_GND_C10-16D3-96B10-16_OB7-62XC5-08B'| 'IO'  | 'GND_C10-16D3-96B10-16_OB7-62XC5-08B_FOR SEL'     | ''             | ''          | ''           
 'TH'      | 'EMPTY'  | 'GND_HOLE430'(!)        = ''       | ''        | 'GND_HOLE430'           |'GND_C10D3-5B10_OB28XC5B'| 'IO'  | 'GND_C10D3-5B10_OB28XC5B'                         | ''             | ''          | ''           
 'TH'      | 'EMPTY'  | 'GND_HOLE433'(!)        = ''       | ''        | 'GND_HOLE433'           |'GND_C10-16D3-66B10-16_OB7-62XC5-08B'| 'IO'  | 'GND_C10-16D3-66B10-16_OB7-62XC5-08B'             | ''             | ''          | ''           
 'TH'      | 'EMPTY'  | 'SP_GND_HOLE433'(!)     = ''       | ''        | 'GND_HOLE433'           |'G_GND_C10-16D3-66B10-16_OB7-62XC5-08B'| 'IO'  | 'GND_C10-16D3-66B10-16_OB7-62XC5-08B_FOR SEL'     | ''             | ''          | ''           
 'TH'      | 'EMPTY'  | 'SP_GND_HOLE46'(!)      = ''       | ''        | 'GND_HOLE46'            |'G_GND_C10D4B10'| 'IO'  | 'GNDHOLE_8PIN_C10D4B10_FOR SEL'                   | ''             | ''          | ''           
 'TH'      | 'EMPTY'  | 'GND_HOLE429'(!)        = ''       | ''        | 'GND_HOLE429'           |'GND_C10OBD4-4X4-8B10'| 'IO'  | 'GND_C10OBD4-4X4-8B10'                            | ''             | ''          | ''           
 'TH'      | 'EMPTY'  | 'GND_HOLE343'(!)        = ''       | ''        | 'GND_HOLE343'           |'GND_C10D4-4B10'| 'IO'  | 'GND_C10D4-4B10'                                  | ''             | ''          | ''           
 'TH'      | 'EMPTY'  | 'GND_HOLE438'(!)        = ''       | ''        | 'GND_HOLE438'           |'GND_C10-16D4B10-16_OB3-81XC5-08B'| 'IO'  | 'GND_C10-16D4B10-16_OB3-81XC5-08B'                | ''             | ''          | ''           
 'TH'      | 'EMPTY'  | 'SP_GND_HOLE438'(!)     = ''       | ''        | 'GND_HOLE438'           |'G_GND_C10-16D4B10-16_OB3-81XC5-08B'| 'IO'  | 'G_GND_C10-16D4B10-16_OB3-81XC5-08B_FOR SEL'      | ''             | ''          | ''           
 'TH'      | 'EMPTY'  | 'GND_HOLE431'(!)        = ''       | ''        | 'GND_HOLE431'           |'GND_C8D3-3B8'| 'IO'  | 'GND_C8D3-3B8'                                    | ''             | ''          | ''           
 'TH'      | 'EMPTY'  | 'GND_HOLE313'(!)        = ''       | ''        | 'GND_HOLE313'           |'GND_C10D4B10_OB7XC5B'| 'IO'  | 'GND_C10D4B10_OB7XC5B'                            | ''             | ''          | ''           
 'TH'      | 'EMPTY'  | 'GND_HOLE439'(!)        = ''       | ''        | 'GND_HOLE439'           |'GND_C10D7B10'| 'IO'  | 'GND_C10D7B10'                                    | ''             | ''          | ''           
 'TH'      | 'EMPTY'  | 'GND_HOLE442'(!)        = ''       | ''        | 'GND_HOLE442'           |'G_GND_C9D5-28B9'| 'IO'  | 'GND_C9D5-28B9 (FOR SEL)'                         | ''             | ''          | ''           
 'TH'      | 'EMPTY'  | 'GND_HOLE453'(!)        = ''       | ''        | 'GND_HOLE453'           |'GND_C10D4B10_OB3-5XC5B'| 'IO'  | 'GND_C10D4B10_OB3-5XC5B'                          | ''             | ''          | ''           
 'TH'      | 'EMPTY'  | 'GND_HOLE455'(!)        = ''       | ''        | 'GND_HOLE455'           |'GND_C8D3-2B12'| 'IO'  | 'GND_C8D3-2B12'                                   | ''             | ''          | ''           
 'TH'      | 'EMPTY'  | 'GND_HOLE456'(!)        = ''       | ''        | 'GND_HOLE456'           |'GND_C8OBD4X5-5_OB1-5XC4T'| 'IO'  | 'GND_C8OBD4X5-5_OB1-5XC4T'                        | ''             | ''          | ''           
 'TH'      | 'EMPTY'  | 'GND_HOLE457'(!)        = ''       | ''        | 'GND_HOLE457'           |'GND_C8D4T'| 'IO'  | 'GND_C8D4T'                                       | ''             | ''          | ''           
 'TH'      | 'EMPTY'  | 'GND_HOLE354'(!)        = ''       | ''        | 'GND_HOLE354'           |'GND_C9D3-6B9_OB4XC4-5B'| 'IO'  | 'GND_C9D3-6B9_OB4XC4-5B'                          | ''             | ''          | ''           
 'TH'      | 'EMPTY'  | 'GND_HOLE464'(!)        = ''       | ''        | 'GND_HOLE464'           |'GND_C10D3-2B_RB'| 'IO'  | 'GND_C10D3-2B_RB'                                 | ''             | ''          | ''           
 'TH'      | 'EMPTY'  | 'GND_HOLE468'(!)        = ''       | ''        | 'GND_HOLE468'           |'GND_C10D3-8B10_OB4-5XC5B'| 'IO'  | 'GND_C10D3-8B10_OB4-5XC5B'                        | ''             | ''          | ''           
 'TH'      | 'EMPTY'  | 'GND_HOLE469'(!)        = ''       | ''        | 'GND_HOLE469'           |'GND_C9D3-5T'| 'IO'  | 'GND_C9D3-5T'                                     | ''             | ''          | ''           
 'TH'      | 'EMPTY'  | 'GND_HOLE470'(!)        = ''       | ''        | 'GND_HOLE470'           |'GND_C10D3-3B8_OB3-5XC4B'| 'IO'  | 'GND_C10D3-3B8_OB3-5XC4B'                         | ''             | ''          | ''           
 'TH'      | 'EMPTY'  | 'GND_HOLE474'(!)        = ''       | ''        | 'GND_HOLE474'           |'GND_C10OBD5-7X6-7B10'| 'IO'  | 'GND_C10OBD5-7X6-7B10'                            | ''             | ''          | ''           
 'TH'      | 'EMPTY'  | 'GND_HOLE475'(!)        = ''       | ''        | 'GND_HOLE475'           |'GND_OB10X10-4OBD5-7X6-1B10X10-4'| 'IO'  | 'GND_OB10X10-4OBD5-7X6-1B10X10-4'                 | ''             | ''          | ''           
 'TH'      | 'EMPTY'  | 'GND_HOLE477'(!)        = ''       | ''        | 'GND_HOLE477'           |'GND_C10D5-7B9'| 'IO'  | 'GND_C10D5-7B9'                                   | ''             | ''          | ''           
 'TH'      | 'EMPTY'  | 'GND_HOLE478'(!)        = ''       | ''        | 'GND_HOLE478'           |'GND_C9D4-3B11_OB6XC4-5T_RB'| 'IO'  | 'GND_C9D4-3B11_OB6XC4-5T_RB'                      | ''             | ''          | ''           
 'TH'      | 'EMPTY'  | 'GND_HOLE479'(!)        = ''       | ''        | 'GND_HOLE479'           |'GND_C9D3-3B6_OB6XC3B'| 'IO'  | 'GND_C9D3-3B6_OB6XC3B'                            | ''             | ''          | ''           
 'TH'      | 'EMPTY'  | 'GND_HOLE486'(!)        = ''       | ''        | 'GND_HOLE486'           |'GND_C10D3-7B10'| 'IO'  | 'GND_C10D3-7B10'                                  | ''             | ''          | ''           
 'TH'      | 'EMPTY'  | 'GND_HOLE148'(!)        = ''       | ''        | 'GND_HOLE148'           |'GND_C10D4-4'| 'IO'  | 'GND_C10D4-4'                                     | ''             | ''          | ''           
 'TH'      | 'EMPTY'  | 'GND_HOLE233'(!)        = ''       | ''        | 'GND_HOLE233'           |'GND_C10-16D4-7B10-16'| 'IO'  | 'GNDHOLE_8PIN_C10-16D4-7B10-16'                   | ''             | ''          | ''           
 'TH'      | 'EMPTY'  | 'GND_HOLE489'(!)        = ''       | ''        | 'GND_HOLE489'           |'GND_C10D3-8B10_OB7XC5B'| 'IO'  | 'GND_C10D3-8B10_OB7XC5B'                          | ''             | ''          | ''           
 'TH'      | 'EMPTY'  | 'GND_HOLE490'(!)        = ''       | ''        | 'GND_HOLE490'           |'GND_C9D3-3B9'| 'IO'  | 'GND_C9D3-3B9'                                    | ''             | ''          | ''           
 'TH'      | 'EMPTY'  | 'GND_HOLE452'(!)        = ''       | ''        | 'GND_HOLE452'           |'GND_C6D2-7B6'| 'IO'  | 'GND_C6D2-7B6'                                    | ''             | ''          | ''           
 'TH'      | 'EMPTY'  | 'GND_HOLE493'(!)        = ''       | ''        | 'GND_HOLE493'           |'GND_C10D4B10_OB3-5XC5'| 'IO'  | 'GND_C10D4B10_OB3-5XC5'                           | ''             | ''          | ''           
 'TH'      | 'EMPTY'  | 'GND_HOLE494'(!)        = ''       | ''        | 'GND_HOLE494'           |'GND_C10D3-7B10_RB'| 'IO'  | 'GND_C10D3-7B10_RB'                               | ''             | ''          | ''           
 'TH'      | 'EMPTY'  | 'GND_HOLE497'(!)        = ''       | ''        | 'GND_HOLE497'           |'GND_C9D4B9_OB3-7XC4-5B'| 'IO'  | 'GND_C9D4B9_OB3-7XC4-5B'                          | ''             | ''          | ''           
 'TH'      | 'EMPTY'  | 'GND_HOLE498'(!)        = ''       | ''        | 'GND_HOLE498'           |'GND_C5D2-4T'| 'IO'  | 'GND_C5D2-4T'                                     | ''             | ''          | ''           
 'TH'      | 'EMPTY'  | 'GND_HOLE499'(!)        = ''       | ''        | 'GND_HOLE499'           |'GND_C10D3-18B10_RB'| 'IO'  | 'GND_C10D3-18B10_RB'                              | ''             | ''          | ''           
 'TH'      | 'EMPTY'  | 'GND_HOLE173'(!)        = ''       | ''        | 'GND_HOLE173'           |'GND_C10D4-2B10'| 'IO'  | 'GNDHOLE_8PIN_C10D4-2B10'                         | ''             | ''          | ''           
 'TH'      | 'EMPTY'  | 'GND_HOLE368'(!)        = ''       | ''        | 'GND_HOLE368'           |'GND_C10D4B10_OB6XC5'| 'IO'  | 'GND_C10D4B10_OB6XC5'                             | ''             | ''          | ''           
 'TH'      | 'EMPTY'  | 'GND_HOLE443'(!)        = ''       | ''        | 'GND_HOLE443'           |'GND_C8D5-6B8_OB3-5XC4T_RB'| 'IO'  | 'GND_C8D5-6B8_OB3-5XC4T_RB'                       | ''             | ''          | ''           
 'TH'      | 'EMPTY'  | 'GND_HOLE32'(!)         = ''       | ''        | 'GND_HOLE32'            |'GND_C10D3-3B10'| 'IO'  | 'GND_C10D3-3B10'                                  | ''             | ''          | ''           
 'TH'      | 'EMPTY'  | 'GND_HOLE226'(!)        = ''       | ''        | 'GND_HOLE226'           |'GND_C7D3-18B7'| 'IO'  | 'GND_C7D3-18B7'                                   | ''             | ''          | ''           
 'TH'      | 'EMPTY'  | 'GND_HOLE501'(!)        = ''       | ''        | 'GND_HOLE501'           |'GND_C10-25D3-7B9_OB12X4-5B'| 'IO'  | 'GND_C10-25D3-7B9_OB12X4-5B'                      | ''             | ''          | ''           
 'TH'      | 'EMPTY'  | 'GND_HOLE502'(!)        = ''       | ''        | 'GND_HOLE502'           |'GND_C7D2B_RB'| 'IO'  | 'GND_C7D2B_RB'                                    | ''             | ''          | ''           
 'TH'      | 'EMPTY'  | 'GND_HOLE106'(!)        = ''       | ''        | 'GND_HOLE106'           |'GND_C10D4'| 'IO'  | 'GND_C10D4'                                       | ''             | ''          | ''           
 'TH'      | 'EMPTY'  | 'GND_HOLE435'(!)        = ''       | ''        | 'GND_HOLE435'           |'GND_C10-26D4-06B10-26'| 'IO'  | 'GND_C10-26D4-06B10-26'                           | ''             | ''          | ''           
 'TH'      | 'EMPTY'  | 'GND_HOLE503'(!)        = ''       | ''        | 'GND_HOLE503'           |'GND_C5-5D3-2B7'| 'IO'  | 'GND_C5-5D3-2B7'                                  | ''             | ''          | ''           
 'TH'      | 'EMPTY'  | 'GND_HOLE505'(!)        = ''       | ''        | 'GND_HOLE505'           |'GND_C10OBD4-8X5-2B10'| 'IO'  | 'GND_C10OBD4-8X5-2B10'                            | ''             | ''          | ''           
 'TH'      | 'EMPTY'  | 'GND_HOLE506'(!)        = ''       | ''        | 'GND_HOLE506'           |'GND_OB10X10-4OBD4-8X5-2B10X10-4_RB'| 'IO'  | 'GND_OB10X10-4OBD4-8X5-2B10X10-4_RB'              | ''             | ''          | ''           
 'TH'      | 'EMPTY'  | 'GND_HOLE507'(!)        = ''       | ''        | 'GND_HOLE507'           |'GND_C11D3-2B11_RB'| 'IO'  | 'GND_C11D3-2B11_RB'                               | ''             | ''          | ''           
 'TH'      | 'EMPTY'  | 'GND_HOLE508'(!)        = ''       | ''        | 'GND_HOLE508'           |'GND_C8D3-175B8_RB'| 'IO'  | 'GND_C8D3-175B8_RB'                               | ''             | ''          | ''           
 'TH'      | 'EMPTY'  | 'GND_HOLE509'(!)        = ''       | ''        | 'GND_HOLE509'           |'GND_C8D4-9B8_RB'| 'IO'  | 'GND_C8D4-9B8_RB'                                 | ''             | ''          | ''           
 'TH'      | 'EMPTY'  | 'GND_HOLE437'(!)        = ''       | ''        | 'GND_HOLE437'           |'GND_C10D6-4B10_OB10-5XC5B'| 'IO'  | 'GND_C10D6-4B10_OB10-5XC5B'                       | ''             | ''          | ''           
 'TH'      | 'EMPTY'  | 'GND_HOLE511'(!)        = ''       | ''        | 'GND_HOLE511'           |'GND_C9D4B9_OB4-5XC4-5B'| 'IO'  | 'GND_C9D4B9_OB4-5XC4-5B'                          | ''             | ''          | ''           
 'TH'      | 'EMPTY'  | 'GND_HOLE512'(!)        = ''       | ''        | 'GND_HOLE512'           |'G_GND_C12-7D3-58B_OB10-92XC6-35_IY2-03'| 'IO'  | 'G_GND_C12-7D3-58B_OB10-92XC6-35_IY2-03'          | ''             | ''          | ''           
 'TH'      | 'EMPTY'  | 'GND_HOLE513'(!)        = ''       | ''        | 'GND_HOLE513'           |'G_GND_OB12-7X23-62OBD3-58X5-08B_IY2-03'| 'IO'  | 'G_GND_OB12-7X23-62OBD3-58X5-08B_IY2-03'          | ''             | ''          | ''           
 'TH'      | 'EMPTY'  | 'GND_HOLE514'(!)        = ''       | ''        | 'GND_HOLE514'           |'GND_C10D6-5B10_NPM_RB_NSP'| 'IO'  | 'GND_C10D6-5B10_NPM_RB_NSP'                       | ''             | ''          | ''           
 'TH'      | 'EMPTY'  | 'GND_HOLE280'(!)        = ''       | ''        | 'GND_HOLE280'           |'GND_BOT10-16D3-96_O7-62XC10-16B'| 'IO'  | 'GND_BOT10-16D3-96_O7-62xC10-16B'                 | ''             | ''          | ''           
 'TH'      | 'EMPTY'  | 'GND_HOLE472'(!)        = ''       | ''        | 'GND_HOLE472'           |'GND_C10D3-3B10_OB5XC5B'| 'IO'  | 'GND_C10D3-3B10_OB5XC5B'                          | ''             | ''          | ''           
 'TH'      | 'EMPTY'  | 'GND_HOLE136'(!)        = ''       | ''        | 'GND_HOLE136'           |'G-GND_C8D4'| 'IO'  | 'G-GND_C8D4'                                      | ''             | ''          | ''           
 'TH'      | 'EMPTY'  | 'GND_HOLE515'(!)        = ''       | ''        | 'GND_HOLE515'           |'GND_C5D2-5B_RB'| 'IO'  | 'GND_C5D2-5B_RB'                                  | ''             | ''          | ''           
 'TH'      | 'EMPTY'  | 'GND_HOLE516'(!)        = ''       | ''        | 'GND_HOLE516'           |'GND_C9-5D6-5B9-5'| 'IO'  | 'GND_C9-5D6-5B9-5'                                | ''             | ''          | ''           
 'TH'      | 'EMPTY'  | 'GND_HOLE467'(!)        = ''       | ''        | 'GND_HOLE467'           |'GND_C9D6-4B9_T0-08_-0_M_PLT13-5_NUT'| 'IO'  | 'GND_C9D6-4B9_T0-08_-0_M_PLT13-5_NUT'             | ''             | ''          | ''           
 'TH'      | 'EMPTY'  | 'SP_GND_HOLE467'(!)     = ''       | ''        | 'GND_HOLE467'           |'G_GND_C9D6-4B9_T0-08_-0_M_PLT13-5_NUT'| 'IO'  | 'G_GND_C9D6-4B9_T0-08_-0_M_PLT13-5_NUT (FOR SEL)' | ''             | ''          | ''           
 'TH'      | 'EMPTY'  | 'GND_HOLE517'(!)        = ''       | ''        | 'GND_HOLE517'           |'GND_C9D6-4B9'| 'IO'  | 'GND_C9D6-4B9'                                    | ''             | ''          | ''           
 'TH'      | 'EMPTY'  | 'SP_GND_HOLE517'(!)     = ''       | ''        | 'GND_HOLE517'           |'G_GND_C9D6-4B9'| 'IO'  | 'G_GND_C9D6-4B9'                                  | ''             | ''          | ''           
 'TH'      | 'EMPTY'  | 'GND_HOLE487'(!)        = ''       | ''        | 'GND_HOLE487'           |'GND_C7-3D3-4B7-3'| 'IO'  | 'GND_C7-3D3-4B7-3'                                | ''             | ''          | ''           
 'TH'      | 'EMPTY'  | 'GND_HOLE34'(!)         = ''       | ''        | 'GND_HOLE34'            |'GND_C8D5-2B8'| 'IO'  | 'GND_C8D5-2B8'                                    | ''             | ''          | ''           
 'TH'      | 'EMPTY'  | 'GND_HOLE331'(!)        = ''       | ''        | 'GND_HOLE331'           |'GND_C8D4-2B10_OB7XC5B'| 'IO'  | 'GND_C8D4-2B10_OB7XC5B'                           | ''             | ''          | ''           
 'TH'      | 'EMPTY'  | 'GND_HOLE31'(!)         = ''       | ''        | 'GND_HOLE31'            |'GND_C10D5-2B10'| 'IO'  | 'GND_C10D5-2B10'                                  | ''             | ''          | ''           
 'TH'      | 'EMPTY'  | 'GND_HOLE521'(!)        = ''       | ''        | 'GND_HOLE521'           |'GND_C10OBD5-2X5-7B10'| 'IO'  | 'GND_C10OBD5-2X5-7B10'                            | ''             | ''          | ''           
 'TH'      | 'EMPTY'  | 'SP_GND_HOLE226'(!)     = ''       | ''        | 'GND_HOLE226'           |'G_GND_C7D3-18B7'| 'IO'  | 'GNDHOLE_8PIN_C7D3-18B7'                          | ''             | ''          | ''           
 'TH'      | 'EMPTY'  | 'GND_HOLE12'(!)         = ''       | ''        | 'GND_HOLE12'            |'GND_C8D4B8'| 'IO'  | 'GND_C8D4B8'                                      | ''             | ''          | ''           
 'TH'      | 'EMPTY'  | 'GND_HOLE473'(!)        = ''       | ''        | 'GND_HOLE473'           |'GND_C10D3-3B10_OB8XC5B'| 'IO'  | 'GND_C10D3-3B10_OB8XC5B'                          | ''             | ''          | ''           
 'TH'      | 'EMPTY'  | 'GND_HOLE109'(!)        = ''       | ''        | 'GND_HOLE109'           |'GND_C9D3-4B9'| 'IO'  | 'GNDHOLE_8PIN_C9D3-4B9'                           | ''             | ''          | ''           
 'TH'      | 'EMPTY'  | 'GND_HOLE522'(!)        = ''       | ''        | 'GND_HOLE522'           |'GND_OB10X10-7OBD4-5X5-2B10X10-7'| 'IO'  | 'GND_OB10X10-7OBD4-5X5-2B10X10-7'                 | ''             | ''          | ''           
 'TH'      | 'EMPTY'  | 'GND_HOLE523'(!)        = ''       | ''        | 'GND_HOLE523'           |'GND_C10D3-7B10_OB22XC5T_RB'| 'IO'  | 'GND_C10D3-7B10_OB22XC5T_RB'                      | ''             | ''          | ''           
 'TH'      | 'EMPTY'  | 'SP_GND_HOLE523'(!)     = ''       | ''        | 'GND_HOLE523'           |'G_GND_C10D3-7B10_OB22XC5T_RB'| 'IO'  | 'G_GND_C10D3-7B10_OB22XC5T_RB (FOR SEL)'          | ''             | ''          | ''           
 'TH'      | 'EMPTY'  | 'GND_HOLE524'(!)        = ''       | ''        | 'GND_HOLE524'           |'GND_C10D4B10_OB22XC5T_RB'| 'IO'  | 'GND_C10D4B10_OB22XC5T_RB'                        | ''             | ''          | ''           
 'TH'      | 'EMPTY'  | 'SP_GND_HOLE524'(!)     = ''       | ''        | 'GND_HOLE524'           |'G_GND_C10D4B10_OB22XC5T_RB'| 'IO'  | 'G_GND_C10D4B10_OB22XC5T_RB (FOR SEL)'            | ''             | ''          | ''           
 'TH'      | 'EMPTY'  | 'GND_HOLE254'(!)        = ''       | ''        | 'GND_HOLE254'           |'GND_C6D3B6'| 'IO'  | 'GND_C6D3B6'                                      | ''             | ''          | ''           
 'TH'      | 'EMPTY'  | 'SP_GND_HOLE254'(!)     = ''       | ''        | 'GND_HOLE254'           |'G_GND_C6D3B6'| 'IO'  | 'G_GND_C6D3B6 (FOR SEL)'                          | ''             | ''          | ''           
 'TH'      | 'EMPTY'  | 'GND_HOLE525'(!)        = ''       | ''        | 'GND_HOLE525'           |'GND_C8-5D4-5B8-5'| 'IO'  | 'GND_C8-5D4-5B8-5'                                | ''             | ''          | ''           
 'TH'      | 'EMPTY'  | 'GND_HOLE526'(!)        = ''       | ''        | 'GND_HOLE526'           |'GND_C8-5D3-7B8-5'| 'IO'  | 'GND_C8-5D3-7B8-5'                                | ''             | ''          | ''           
 'TH'      | 'EMPTY'  | 'GND_HOLE527'(!)        = ''       | ''        | 'GND_HOLE527'           |'GND_C10D4-5B10_OB5XC5B'| 'IO'  | 'GND_C10D4-5B10_OB5XC5B'                          | ''             | ''          | ''           
 'TH'      | 'EMPTY'  | 'SP_GND_HOLE527'(!)     = ''       | ''        | 'GND_HOLE527'           |'G_GND_C10D4-5B10_OB5XC5B'| 'IO'  | 'G_GND_C10D4-5B10_OB5XC5B (FOR SEL)'              | ''             | ''          | ''           
 'TH'      | 'EMPTY'  | 'GND_HOLE528'(!)        = ''       | ''        | 'GND_HOLE528'           |'GND_S12D3-7B10_IX-2T'| 'IO'  | 'GND_S12D3-7B10_IX-2T'                            | ''             | ''          | ''           
 'TH'      | 'EMPTY'  | 'SP_GND_HOLE528'(!)     = ''       | ''        | 'GND_HOLE528'           |'G_GND_S12D3-7B10_IX-2T'| 'IO'  | 'G_GND_S12D3-7B10_IX-2T (FOR SEL)'                | ''             | ''          | ''           
 'TH'      | 'EMPTY'  | 'GND_HOLE529'(!)        = ''       | ''        | 'GND_HOLE529'           |'GND_C10OBD4-5X5B10_OB5XC5B'| 'IO'  | 'GND_C10OBD4-5X5B10_OB5XC5B'                      | ''             | ''          | ''           
 'TH'      | 'EMPTY'  | 'SP_GND_HOLE529'(!)     = ''       | ''        | 'GND_HOLE529'           |'G_GND_C10OBD4-5X5B10_OB5XC5B'| 'IO'  | 'G_GND_C10OBD4-5X5B10_OB5XC5B (FOR SEL)'          | ''             | ''          | ''           
 'TH'      | 'EMPTY'  | 'GND_HOLE530'(!)        = ''       | ''        | 'GND_HOLE530'           |'GND_C10D3-7B10_OB5XC5B'| 'IO'  | 'GND_C10D3-7B10_OB5XC5B'                          | ''             | ''          | ''           
 'TH'      | 'EMPTY'  | 'SP_GND_HOLE530'(!)     = ''       | ''        | 'GND_HOLE530'           |'G_GND_C10D3-7B10_OB5XC5B'| 'IO'  | 'G_GND_C10D3-7B10_OB5XC5B (FOR SEL)'              | ''             | ''          | ''           
 'TH'      | 'EMPTY'  | 'GND_HOLE531'(!)        = ''       | ''        | 'GND_HOLE531'           |'GND_C5-5D2-9B5-5'| 'IO'  | 'GND_C5-5D2-9B5-5'                                | ''             | ''          | ''           

END_PART

END.

